# BASEBOARD_FAB2 (Tioga Pass) — schematic netlist excerpt (pin names and nets, part order shuffled) for the footprints in the layout excerpt that follows; sources: Cadence DE-HDL packaged netlist, KiCad conversion of Wiwynn_Tioga_Pass_MB.brd

C25W57  CAP  100.0PF 50V 5% COG  pkg 0402LF  page 149 : A = VCC_PA_3V3 ; B = GND
C5P30  CAP  100UF 4V 20% X5R  pkg 0805  page 42 : A = PVCCMCP_CPU0 ; B = GND
C6N6  CAP  10UF 16V 10% X6S  pkg 0805  page 205 : A = VR_FET_SW_P12V_STBY_PVCCIN_CPU0 ; B = GND

(kicad_pcb
	(version 20260206)
	(generator "pcbnew")
	(generator_version "10.0")
	(general
		(thickness 1.6)
		(legacy_teardrops no)
	)
	(paper "A4")
	(title_block
		(title "Wiwynn_Tioga_Pass_MB.brd")
		(comment 1 "Tioga Pass / footprints 2634-2636 of 4770")
	)
	(layers
		(0 "F.Cu" signal "TOP")
		(4 "In1.Cu" signal "L2GND")
		(6 "In2.Cu" signal "L3")
		(8 "In3.Cu" signal "L4GND")
		(10 "In4.Cu" signal "L5")
		(12 "In5.Cu" signal "L6GND")
		(14 "In6.Cu" signal "L7VCC")
		(16 "In7.Cu" signal "L8VCC")
		(18 "In8.Cu" signal "L9GND")
		(20 "In9.Cu" signal "L10")
		(22 "In10.Cu" signal "L11GND")
		(24 "In11.Cu" signal "L12")
		(26 "In12.Cu" signal "L13GND")
		(2 "B.Cu" signal "BOTTOM")
		(9 "F.Adhes" user "F.Adhesive")
		(11 "B.Adhes" user "B.Adhesive")
		(13 "F.Paste" user "Package Geometry/Pastemask Top")
		(15 "B.Paste" user "Package Geometry/Pastemask Bottom")
		(5 "F.SilkS" user "Ref Des/Silkscreen Top")
		(7 "B.SilkS" user "Ref Des/Silkscreen Bottom")
		(1 "F.Mask" user "Board Geometry/Soldermask Top")
		(3 "B.Mask" user "Board Geometry/Soldermask Bottom")
		(17 "Dwgs.User" user "User.Drawings")
		(19 "Cmts.User" user "User.Comments")
		(21 "Eco1.User" user "User.Eco1")
		(23 "Eco2.User" user "User.Eco2")
		(25 "Edge.Cuts" user "Board Geometry/Outline")
		(27 "Margin" user)
		(31 "F.CrtYd" user "Package Geometry/Place Bound Top")
		(29 "B.CrtYd" user "Package Geometry/Place Bound Bottom")
		(35 "F.Fab" user "Ref Des/Assembly Top")
		(33 "B.Fab" user "Ref Des/Assembly Bottom")
	)
	(footprint ""
		(layer "B.Cu")
		(at 271.350486 -73.51014)
		(property "Reference" "C5P30"
			(at 0 0 0)
			(layer "B.SilkS")
			(hide yes)
			(effects
				(font
					(size 1.27 1.27)
				)
				(justify mirror)
			)
		)
		(property "Value" ""
			(at 0 0 0)
			(layer "B.Fab")
			(effects
				(font
					(size 1.27 1.27)
				)
				(justify mirror)
			)
		)
		(duplicate_pad_numbers_are_jumpers no)
		(fp_poly
			(pts
				(xy 0.7239 -0.2159) (xy -0.7239 -0.2159) (xy -0.7239 1.9939) (xy 0.7239 1.9939)
			)
			(stroke
				(width 0)
				(type default)
			)
			(fill no)
			(layer "B.CrtYd")
		)
		(fp_line
			(start -0.7239 -0.2159)
			(end 0.7239 -0.2159)
			(stroke
				(width 0.1)
				(type default)
			)
			(layer "B.Fab")
		)
		(fp_line
			(start -0.7239 1.9939)
			(end -0.7239 -0.2159)
			(stroke
				(width 0.1)
				(type default)
			)
			(layer "B.Fab")
		)
		(fp_line
			(start 0.7239 -0.2159)
			(end 0.7239 1.9939)
			(stroke
				(width 0.1)
				(type default)
			)
			(layer "B.Fab")
		)
		(fp_line
			(start 0.7239 1.9939)
			(end -0.7239 1.9939)
			(stroke
				(width 0.1)
				(type default)
			)
			(layer "B.Fab")
		)
		(pad "1" smd rect
			(at 0 0 180)
			(size 1.27 1.016)
			(layers "B.Cu" "B.Mask" "B.Paste")
			(net "PVCCMCP_CPU0")
		)
		(pad "2" smd rect
			(at 0 1.778 180)
			(size 1.27 1.016)
			(layers "B.Cu" "B.Mask" "B.Paste")
			(net "GND")
		)
		(zone
			(layer "B.Cu")
			(hatch none 0.5)
			(connect_pads
				(clearance 0)
			)
			(min_thickness 0.25)
			(keepout
				(tracks not_allowed)
				(vias allowed)
				(pads allowed)
				(copperpour not_allowed)
				(footprints allowed)
			)
			(placement
				(enabled no)
				(sheetname "")
			)
			(fill
				(thermal_gap 0.5)
				(thermal_bridge_width 0.5)
				(island_removal_mode 0)
			)
			(polygon
				(pts
					(xy 271.985486 -73.00214) (xy 270.715486 -73.00214) (xy 270.715486 -72.24014) (xy 271.985486 -72.24014)
				)
			)
		)
	)
	(footprint ""
		(layer "B.Cu")
		(at 197.866 -97.282 90)
		(property "Reference" "C6N6"
			(at 0 0 90)
			(layer "B.SilkS")
			(hide yes)
			(effects
				(font
					(size 1.27 1.27)
				)
				(justify mirror)
			)
		)
		(property "Value" ""
			(at 0 0 90)
			(layer "B.Fab")
			(effects
				(font
					(size 1.27 1.27)
				)
				(justify mirror)
			)
		)
		(duplicate_pad_numbers_are_jumpers no)
		(fp_rect
			(start -0.7239 -0.2159)
			(end 0.7239 1.9939)
			(stroke
				(width 0)
				(type default)
			)
			(fill no)
			(layer "B.CrtYd")
		)
		(fp_line
			(start 0.7239 -0.2159)
			(end 0.7239 1.9939)
			(stroke
				(width 0.1)
				(type default)
			)
			(layer "B.Fab")
		)
		(fp_line
			(start -0.7239 -0.2159)
			(end 0.7239 -0.2159)
			(stroke
				(width 0.1)
				(type default)
			)
			(layer "B.Fab")
		)
		(fp_line
			(start 0.7239 1.9939)
			(end -0.7239 1.9939)
			(stroke
				(width 0.1)
				(type default)
			)
			(layer "B.Fab")
		)
		(fp_line
			(start -0.7239 1.9939)
			(end -0.7239 -0.2159)
			(stroke
				(width 0.1)
				(type default)
			)
			(layer "B.Fab")
		)
		(pad "1" smd rect
			(at 0 0 270)
			(size 1.27 1.016)
			(layers "B.Cu" "B.Mask" "B.Paste")
			(net "VR_FET_SW_P12V_STBY_PVCCIN_CPU0")
		)
		(pad "2" smd rect
			(at 0 1.778 270)
			(size 1.27 1.016)
			(layers "B.Cu" "B.Mask" "B.Paste")
			(net "GND")
		)
		(zone
			(layer "B.Cu")
			(hatch none 0.5)
			(connect_pads
				(clearance 0)
			)
			(min_thickness 0.25)
			(keepout
				(tracks not_allowed)
				(vias allowed)
				(pads allowed)
				(copperpour not_allowed)
				(footprints allowed)
			)
			(placement
				(enabled no)
				(sheetname "")
			)
			(fill
				(thermal_gap 0.5)
				(thermal_bridge_width 0.5)
				(island_removal_mode 0)
			)
			(polygon
				(pts
					(xy 198.374 -96.647) (xy 199.136 -96.647) (xy 199.136 -97.917) (xy 198.374 -97.917)
				)
			)
		)
	)
	(footprint ""
		(layer "B.Cu")
		(at 422.574974 -40.982646 180)
		(property "Reference" "C25W57"
			(at 0.8382 -0.67818 180)
			(unlocked yes)
			(layer "B.SilkS")
			(effects
				(font
					(size 0.4064 0.254)
					(thickness 0.1524)
				)
				(justify left mirror)
			)
		)
		(property "Value" ""
			(at 0 0 0)
			(layer "B.Fab")
			(effects
				(font
					(size 1.27 1.27)
				)
				(justify mirror)
			)
		)
		(duplicate_pad_numbers_are_jumpers no)
		(fp_poly
			(pts
				(xy -0.3048 -0.1016) (xy -0.3048 0.9906) (xy 0.3048 0.9906) (xy 0.3048 -0.1016)
			)
			(stroke
				(width 0)
				(type default)
			)
			(fill no)
			(layer "B.CrtYd")
		)
		(fp_line
			(start 0.3048 0.9906)
			(end -0.3048 0.9906)
			(stroke
				(width 0.1)
				(type default)
			)
			(layer "B.Fab")
		)
		(fp_line
			(start 0.3048 -0.1016)
			(end 0.3048 0.9906)
			(stroke
				(width 0.1)
				(type default)
			)
			(layer "B.Fab")
		)
		(fp_line
			(start -0.3048 0.9906)
			(end -0.3048 -0.1016)
			(stroke
				(width 0.1)
				(type default)
			)
			(layer "B.Fab")
		)
		(fp_line
			(start -0.3048 -0.1016)
			(end 0.3048 -0.1016)
			(stroke
				(width 0.1)
				(type default)
			)
			(layer "B.Fab")
		)
		(pad "1" smd rect
			(at 0 0)
			(size 0.508 0.508)
			(layers "B.Cu" "B.Mask" "B.Paste")
			(net "VCC_PA_3V3")
		)
		(pad "2" smd rect
			(at 0 0.889)
			(size 0.508 0.508)
			(layers "B.Cu" "B.Mask" "B.Paste")
			(net "GND")
		)
		(zone
			(layer "B.Cu")
			(hatch none 0.5)
			(connect_pads
				(clearance 0)
			)
			(min_thickness 0.25)
			(keepout
				(tracks not_allowed)
				(vias allowed)
				(pads allowed)
				(copperpour not_allowed)
				(footprints allowed)
			)
			(placement
				(enabled no)
				(sheetname "")
			)
			(fill
				(thermal_gap 0.5)
				(thermal_bridge_width 0.5)
				(island_removal_mode 0)
			)
			(polygon
				(pts
					(xy 422.320974 -41.617646) (xy 422.828974 -41.617646) (xy 422.828974 -41.236646) (xy 422.320974 -41.236646)
				)
			)
		)
		(zone
			(layer "B.Cu")
			(hatch none 0.5)
			(connect_pads
				(clearance 0)
			)
			(min_thickness 0.25)
			(keepout
				(tracks allowed)
				(vias not_allowed)
				(pads allowed)
				(copperpour not_allowed)
				(footprints allowed)
			)
			(placement
				(enabled no)
				(sheetname "")
			)
			(fill
				(thermal_gap 0.5)
				(thermal_bridge_width 0.5)
				(island_removal_mode 0)
			)
			(polygon
				(pts
					(xy 422.320974 -41.236646) (xy 422.828974 -41.236646) (xy 422.828974 -41.617646) (xy 422.320974 -41.617646)
				)
			)
		)
	)
)
